# BASEBOARD_FAB2 (Tioga Pass) — schematic netlist excerpt (pin names and nets, part order shuffled) for the footprints in the layout excerpt that follows; sources: Cadence DE-HDL packaged netlist, KiCad conversion of Wiwynn_Tioga_Pass_MB.brd

R7C5  RES  10.0K 1% CHIP  pkg 0402  page 133 : A = P3V3_STBY ; B = FM_SINT_PRSNT_N
C4D9  CAP  0.220UF 16V 10% X7R  pkg 0402  page 203 : A = VR_PVCCIN_CPU0_PH4_BOOT ; B = VR_PVCCIN_CPU0_PH4_PHASE
R25W126  RES  150.0 1% CHIP  pkg 0402  page 252 : A = V_IO_B_J ; B = GND

(kicad_pcb
	(version 20260206)
	(generator "pcbnew")
	(generator_version "10.0")
	(general
		(thickness 1.6)
		(legacy_teardrops no)
	)
	(paper "A4")
	(title_block
		(title "Wiwynn_Tioga_Pass_MB.brd")
		(comment 1 "Tioga Pass / footprints 173-175 of 4770")
	)
	(layers
		(0 "F.Cu" signal "TOP")
		(4 "In1.Cu" signal "L2GND")
		(6 "In2.Cu" signal "L3")
		(8 "In3.Cu" signal "L4GND")
		(10 "In4.Cu" signal "L5")
		(12 "In5.Cu" signal "L6GND")
		(14 "In6.Cu" signal "L7VCC")
		(16 "In7.Cu" signal "L8VCC")
		(18 "In8.Cu" signal "L9GND")
		(20 "In9.Cu" signal "L10")
		(22 "In10.Cu" signal "L11GND")
		(24 "In11.Cu" signal "L12")
		(26 "In12.Cu" signal "L13GND")
		(2 "B.Cu" signal "BOTTOM")
		(9 "F.Adhes" user "F.Adhesive")
		(11 "B.Adhes" user "B.Adhesive")
		(13 "F.Paste" user "Package Geometry/Pastemask Top")
		(15 "B.Paste" user "Package Geometry/Pastemask Bottom")
		(5 "F.SilkS" user "Ref Des/Silkscreen Top")
		(7 "B.SilkS" user "Ref Des/Silkscreen Bottom")
		(1 "F.Mask" user "Board Geometry/Soldermask Top")
		(3 "B.Mask" user "Board Geometry/Soldermask Bottom")
		(17 "Dwgs.User" user "User.Drawings")
		(19 "Cmts.User" user "User.Comments")
		(21 "Eco1.User" user "User.Eco1")
		(23 "Eco2.User" user "User.Eco2")
		(25 "Edge.Cuts" user "Board Geometry/Outline")
		(27 "Margin" user)
		(31 "F.CrtYd" user "Package Geometry/Place Bound Top")
		(29 "B.CrtYd" user "Package Geometry/Place Bound Bottom")
		(35 "F.Fab" user "Ref Des/Assembly Top")
		(33 "B.Fab" user "Ref Des/Assembly Bottom")
	)
	(footprint ""
		(layer "F.Cu")
		(at 371.2718 -101.346)
		(property "Reference" "R7C5"
			(at 0 0 0)
			(layer "F.SilkS")
			(hide yes)
			(effects
				(font
					(size 1.27 1.27)
				)
			)
		)
		(property "Value" ""
			(at 0 0 0)
			(layer "F.Fab")
			(effects
				(font
					(size 1.27 1.27)
				)
			)
		)
		(duplicate_pad_numbers_are_jumpers no)
		(fp_poly
			(pts
				(xy -0.2794 -0.1016) (xy 0.2794 -0.1016) (xy 0.2794 0.9906) (xy -0.2794 0.9906)
			)
			(stroke
				(width 0)
				(type default)
			)
			(fill no)
			(layer "F.CrtYd")
		)
		(fp_line
			(start -0.2794 -0.1016)
			(end -0.2794 0.9906)
			(stroke
				(width 0.1)
				(type default)
			)
			(layer "F.Fab")
		)
		(fp_line
			(start -0.2794 0.9906)
			(end 0.2794 0.9906)
			(stroke
				(width 0.1)
				(type default)
			)
			(layer "F.Fab")
		)
		(fp_line
			(start 0.2794 -0.1016)
			(end -0.2794 -0.1016)
			(stroke
				(width 0.1)
				(type default)
			)
			(layer "F.Fab")
		)
		(fp_line
			(start 0.2794 0.9906)
			(end 0.2794 -0.1016)
			(stroke
				(width 0.1)
				(type default)
			)
			(layer "F.Fab")
		)
		(pad "1" smd rect
			(at 0 0)
			(size 0.508 0.508)
			(layers "F.Cu" "F.Mask" "F.Paste")
			(net "P3V3_STBY")
		)
		(pad "2" smd rect
			(at 0 0.889)
			(size 0.508 0.508)
			(layers "F.Cu" "F.Mask" "F.Paste")
			(net "FM_SINT_PRSNT_N")
		)
		(zone
			(layer "F.Cu")
			(hatch none 0.5)
			(connect_pads
				(clearance 0)
			)
			(min_thickness 0.25)
			(keepout
				(tracks allowed)
				(vias not_allowed)
				(pads allowed)
				(copperpour not_allowed)
				(footprints allowed)
			)
			(placement
				(enabled no)
				(sheetname "")
			)
			(fill
				(thermal_gap 0.5)
				(thermal_bridge_width 0.5)
				(island_removal_mode 0)
			)
			(polygon
				(pts
					(xy 371.0178 -101.092) (xy 371.5258 -101.092) (xy 371.5258 -100.711) (xy 371.0178 -100.711)
				)
			)
		)
		(zone
			(layer "F.Cu")
			(hatch none 0.5)
			(connect_pads
				(clearance 0)
			)
			(min_thickness 0.25)
			(keepout
				(tracks not_allowed)
				(vias allowed)
				(pads allowed)
				(copperpour not_allowed)
				(footprints allowed)
			)
			(placement
				(enabled no)
				(sheetname "")
			)
			(fill
				(thermal_gap 0.5)
				(thermal_bridge_width 0.5)
				(island_removal_mode 0)
			)
			(polygon
				(pts
					(xy 371.0178 -100.711) (xy 371.5258 -100.711) (xy 371.5258 -101.092) (xy 371.0178 -101.092)
				)
			)
		)
	)
	(footprint ""
		(layer "F.Cu")
		(at 490.474 -37.338 180)
		(property "Reference" "R25W126"
			(at -0.8382 -0.67818 180)
			(unlocked yes)
			(layer "F.SilkS")
			(effects
				(font
					(size 0.4064 0.254)
					(thickness 0.1524)
				)
				(justify left)
			)
		)
		(property "Value" ""
			(at 0 0 180)
			(layer "F.Fab")
			(effects
				(font
					(size 1.27 1.27)
				)
			)
		)
		(duplicate_pad_numbers_are_jumpers no)
		(fp_poly
			(pts
				(xy -0.2794 -0.1016) (xy 0.2794 -0.1016) (xy 0.2794 0.9906) (xy -0.2794 0.9906)
			)
			(stroke
				(width 0)
				(type default)
			)
			(fill no)
			(layer "F.CrtYd")
		)
		(fp_line
			(start 0.2794 0.9906)
			(end 0.2794 -0.1016)
			(stroke
				(width 0.1)
				(type default)
			)
			(layer "F.Fab")
		)
		(fp_line
			(start 0.2794 -0.1016)
			(end -0.2794 -0.1016)
			(stroke
				(width 0.1)
				(type default)
			)
			(layer "F.Fab")
		)
		(fp_line
			(start -0.2794 0.9906)
			(end 0.2794 0.9906)
			(stroke
				(width 0.1)
				(type default)
			)
			(layer "F.Fab")
		)
		(fp_line
			(start -0.2794 -0.1016)
			(end -0.2794 0.9906)
			(stroke
				(width 0.1)
				(type default)
			)
			(layer "F.Fab")
		)
		(pad "1" smd rect
			(at 0 0 180)
			(size 0.508 0.508)
			(layers "F.Cu" "F.Mask" "F.Paste")
			(net "V_IO_B_J")
		)
		(pad "2" smd rect
			(at 0 0.889 180)
			(size 0.508 0.508)
			(layers "F.Cu" "F.Mask" "F.Paste")
			(net "GND")
		)
		(zone
			(layer "F.Cu")
			(hatch none 0.5)
			(connect_pads
				(clearance 0)
			)
			(min_thickness 0.25)
			(keepout
				(tracks not_allowed)
				(vias allowed)
				(pads allowed)
				(copperpour not_allowed)
				(footprints allowed)
			)
			(placement
				(enabled no)
				(sheetname "")
			)
			(fill
				(thermal_gap 0.5)
				(thermal_bridge_width 0.5)
				(island_removal_mode 0)
			)
			(polygon
				(pts
					(xy 490.728 -37.973) (xy 490.22 -37.973) (xy 490.22 -37.592) (xy 490.728 -37.592)
				)
			)
		)
		(zone
			(layer "F.Cu")
			(hatch none 0.5)
			(connect_pads
				(clearance 0)
			)
			(min_thickness 0.25)
			(keepout
				(tracks allowed)
				(vias not_allowed)
				(pads allowed)
				(copperpour not_allowed)
				(footprints allowed)
			)
			(placement
				(enabled no)
				(sheetname "")
			)
			(fill
				(thermal_gap 0.5)
				(thermal_bridge_width 0.5)
				(island_removal_mode 0)
			)
			(polygon
				(pts
					(xy 490.728 -37.592) (xy 490.22 -37.592) (xy 490.22 -37.973) (xy 490.728 -37.973)
				)
			)
		)
	)
	(footprint ""
		(layer "F.Cu")
		(at 193.7385 -83.212432 90)
		(property "Reference" "C4D9"
			(at 0 0 90)
			(layer "F.SilkS")
			(hide yes)
			(effects
				(font
					(size 1.27 1.27)
				)
			)
		)
		(property "Value" ""
			(at 0 0 90)
			(layer "F.Fab")
			(effects
				(font
					(size 1.27 1.27)
				)
			)
		)
		(duplicate_pad_numbers_are_jumpers no)
		(fp_rect
			(start -0.3048 0.9906)
			(end 0.3048 -0.1016)
			(stroke
				(width 0)
				(type default)
			)
			(fill no)
			(layer "F.CrtYd")
		)
		(fp_line
			(start 0.3048 -0.1016)
			(end -0.3048 -0.1016)
			(stroke
				(width 0.1)
				(type default)
			)
			(layer "F.Fab")
		)
		(fp_line
			(start -0.3048 -0.1016)
			(end -0.3048 0.9906)
			(stroke
				(width 0.1)
				(type default)
			)
			(layer "F.Fab")
		)
		(fp_line
			(start 0.3048 0.9906)
			(end 0.3048 -0.1016)
			(stroke
				(width 0.1)
				(type default)
			)
			(layer "F.Fab")
		)
		(fp_line
			(start -0.3048 0.9906)
			(end 0.3048 0.9906)
			(stroke
				(width 0.1)
				(type default)
			)
			(layer "F.Fab")
		)
		(pad "1" smd rect
			(at 0 0 90)
			(size 0.508 0.508)
			(layers "F.Cu" "F.Mask" "F.Paste")
			(net "VR_PVCCIN_CPU0_PH4_BOOT")
		)
		(pad "2" smd rect
			(at 0 0.889 90)
			(size 0.508 0.508)
			(layers "F.Cu" "F.Mask" "F.Paste")
			(net "VR_PVCCIN_CPU0_PH4_PHASE")
		)
		(zone
			(layer "F.Cu")
			(hatch none 0.5)
			(connect_pads
				(clearance 0)
			)
			(min_thickness 0.25)
			(keepout
				(tracks not_allowed)
				(vias allowed)
				(pads allowed)
				(copperpour not_allowed)
				(footprints allowed)
			)
			(placement
				(enabled no)
				(sheetname "")
			)
			(fill
				(thermal_gap 0.5)
				(thermal_bridge_width 0.5)
				(island_removal_mode 0)
			)
			(polygon
				(pts
					(xy 194.3735 -82.958432) (xy 194.3735 -83.466432) (xy 193.9925 -83.466432) (xy 193.9925 -82.958432)
				)
			)
		)
		(zone
			(layer "F.Cu")
			(hatch none 0.5)
			(connect_pads
				(clearance 0)
			)
			(min_thickness 0.25)
			(keepout
				(tracks allowed)
				(vias not_allowed)
				(pads allowed)
				(copperpour not_allowed)
				(footprints allowed)
			)
			(placement
				(enabled no)
				(sheetname "")
			)
			(fill
				(thermal_gap 0.5)
				(thermal_bridge_width 0.5)
				(island_removal_mode 0)
			)
			(polygon
				(pts
					(xy 194.3735 -82.958432) (xy 194.3735 -83.466432) (xy 193.9925 -83.466432) (xy 193.9925 -82.958432)
				)
			)
		)
	)
)
